FILE_TYPE = CONNECTIVITY;
{Allegro Design Entry HDL 17.2-2016 S081 (4005846) 1/11/2022}
"PAGE_NUMBER" = 232;
0"NC";
1"P3V3_AUX\g";
2"P3V3_AUX\g";
3"P12V_AUX\g";
4"P3V3_AUX\g";
5"P3V3_AUX\g";
6"P3V3_AUX\g";
7"P3V3_AUX\g";
8"GND\g";
9"GND\g";
10"GND\g";
11"GND\g";
12"GND\g";
13"GND\g";
14"GND\g";
15"GND\g";
16"GND\g";
17"GND\g";
18"GND\g";
19"GND\g";
20"FM_COMP_P3V3_STBY_CEXT"CDS_PHYS_NET_NAME"FM_COMP_P3V3_STBY_CEXT";
21"PWRGD_DSW_PWROK_R1"CDS_PHYS_NET_NAME"PWRGD_DSW_PWROK_R1";
22"PWRGD_P3V3_AUX"CDS_PHYS_NET_NAME"PWRGD_P3V3_AUX";
23"PWRGD_P3V3_AUX_R2"CDS_PHYS_NET_NAME"PWRGD_P3V3_AUX_R2";
24"PWRGD_DSW_PWROK"CDS_PHYS_NET_NAME"PWRGD_DSW_PWROK";
25"RST_RSMRST_PCH_N"CDS_PHYS_NET_NAME"RST_RSMRST_PCH_N";
26"FM_PFR_DSW_PWROK_N"CDS_PHYS_NET_NAME"FM_PFR_DSW_PWROK_N";
27"FM_COMP_P3V3_AUX_ENIN"CDS_PHYS_NET_NAME"FM_COMP_P3V3_AUX_ENIN"CDS_PHYS_NET_NAME"FM_COMP_P3V3_AUX_ENIN";
28"FM_COMP_P3V3_AUX_VIN"CDS_PHYS_NET_NAME"FM_COMP_P3V3_AUX_VIN"CDS_PHYS_NET_NAME"FM_COMP_P3V3_AUX_VIN";
29"FM_COMP_P3V3_AUX_VIN_R"CDS_PHYS_NET_NAME"FM_COMP_P3V3_AUX_VIN_R";
30"PWRGD_DSW_PWROK_R1"CDS_PHYS_NET_NAME"PWRGD_DSW_PWROK_R1";
31"PWRGD_DSW_PWROK_R2"CDS_PHYS_NET_NAME"PWRGD_DSW_PWROK_R2";
%"UNIVERSAL_GND"
"1","(-1175,-2725)","0","logical_power","I10";
;
HDL_POWER"GND"
CDS_LIB"logical_power";
"A"11;
%"74LVC1G07SE7"
"1","(-800,-2300)","0","pure_quanta","I11";
;
PART_NUMBER"AL1G07SE000"
MATERIAL"IC"
VALUE"74LVC1G07SE-7"
PART_TYPE"SMLF"
$LOCATION"U95"
SEC_TYPE""
CDS_LIB"pure_quanta"
CDS_LMAN_SYM_OUTLINE"-150,150,150,-150"
NEEDS_NO_SIZE"TRUE"
CDS_LOCATION"U95"
SEC"1";
"NC1"
$PN"1"0;
"Y"
$PN"4"31;
"GND"
$PN"3"11;
"A"
$PN"2"30;
"VCC"
$PN"5"2;
%"UNIVERSAL_POWER"
"1","(-1175,-1750)","0","logical_power","I12";
;
HDL_POWER"P3V3_AUX"
CDS_LIB"logical_power";
"A"2;
%"Q_RES"
"1","(-875,-1500)","0","pure_quanta","I13";
;
PART_NUMBER"CS00002JB13"
PACK_TYPE"0402LF"
WATTAGE"1/16W"
MATERIAL"EMPTY"
TOLERANCE"5%"
VALUE"0"
$LOCATION"R4807"
CDS_LIB"pure_quanta"
CDS_LOCATION"R4807"
$SEC"1"
CDS_SEC"1";
"B"
$PN"2"31;
"A"
$PN"1"30;
%"MOSFET_NCH_GDS_ESD_PROTECTED"
"1","(-150,-225)","2","pure_quanta","I14";
;
PART_NUMBER"BAM70020002"
MATERIAL"IC"
VALUE"2N7002K"
PART_TYPE"SMLF"
LOCATION"Q52"
NEEDS_NO_SIZE"TRUE"
CDS_LMAN_SYM_OUTLINE"-125,150,125,-150"
CDS_LIB"pure_quanta"
$SEC"1"
CDS_SEC"1";
"S"
$PN"S"12;
"G"
$PN"G"23;
"D"
$PN"D"29;
%"UNIVERSAL_GND"
"1","(-175,-625)","0","logical_power","I15";
;
CDS_LIB"logical_power"
HDL_POWER"GND";
"A"12;
%"Q_RES"
"2","(-2250,1650)","2","pure_quanta","I16";
;
PART_NUMBER"CS26192FB03"
MATERIAL"CHIP"
WATTAGE"1/16W"
PACK_TYPE"0402LF"
TOLERANCE"1%"
VALUE"6.19K"
$LOCATION"R1689"
CDS_LIB"pure_quanta"
CDS_LOCATION"R1689"
$SEC"1"
CDS_SEC"1";
"A"
$PN"1"28;
"B"
$PN"2"13;
%"UNIVERSAL_GND"
"1","(-2250,1425)","0","logical_power","I17";
;
CDS_LIB"logical_power"
HDL_POWER"GND";
"A"13;
%"Q_RES"
"2","(-2250,2075)","2","pure_quanta","I18";
;
PART_NUMBER"CS41002FB09"
MATERIAL"CHIP"
VALUE"100K"
PACK_TYPE"0402LF"
WATTAGE"1/16W"
TOLERANCE"1%"
$LOCATION"R1688"
CDS_LIB"pure_quanta"
CDS_LOCATION"R1688"
$SEC"1"
CDS_SEC"1";
"A"
$PN"1"3;
"B"
$PN"2"28;
%"UNIVERSAL_POWER"
"1","(-2250,2400)","0","logical_power","I19";
;
HDL_POWER"P12V_AUX"
CDS_LIB"logical_power";
"A"3;
%"UNIVERSAL_GND"
"1","(-2175,-2775)","0","logical_power","I2";
;
HDL_POWER"GND"
CDS_LIB"logical_power";
"A"8;
%"Q_RES"
"1","(-1600,175)","0","pure_quanta","I20";
;
PART_NUMBER"CS00002JB13"
WATTAGE"1/16W"
MATERIAL"CHIP"
VALUE"0"
TOLERANCE"5%"
PACK_TYPE"0402LF"
$LOCATION"R1950"
CDS_LIB"pure_quanta"
CDS_LOCATION"R1950"
$SEC"1"
CDS_SEC"1";
"B"
$PN"2"29;
"A"
$PN"1"28;
%"Q_RES"
"1","(-1600,425)","0","pure_quanta","I21";
;
PART_NUMBER"CS00002JB13"
PACK_TYPE"0402LF"
VALUE"0"
TOLERANCE"5%"
MATERIAL"EMPTY"
WATTAGE"1/16W"
$LOCATION"R1745"
CDS_LIB"pure_quanta"
CDS_LOCATION"R1745"
$SEC"1"
CDS_SEC"1";
"B"
$PN"2"26;
"A"
$PN"1"27;
%"Q_RES"
"2","(-1850,2075)","0","pure_quanta","I22";
;
PART_NUMBER"CS31002FB08"
VALUE"10K"
TOLERANCE"1%"
WATTAGE"1/16W"
MATERIAL"CHIP"
PACK_TYPE"0402LF"
$LOCATION"R1690"
CDS_LIB"pure_quanta"
CDS_LOCATION"R1690"
$SEC"1"
CDS_SEC"1";
"A"
$PN"1"4;
"B"
$PN"2"27;
%"UNIVERSAL_GND"
"1","(-850,1900)","0","logical_power","I23";
;
HDL_POWER"GND"
CDS_LIB"logical_power";
"A"14;
%"Q_CAP"
"1","(-850,2100)","2","pure_quanta","I24";
;
PART_NUMBER"CH5104KEB02"
VOLTAGE"25V"
MATERIAL"X6S"
TOLERANCE"10%"
PACK_TYPE"C0402"
VALUE"1UF"
$LOCATION"C1315"
CDS_LIB"pure_quanta"
CDS_LOCATION"C1315"
$SEC"1"
CDS_SEC"1";
"B"
$PN"2"14;
"A"
$PN"1"5;
%"TPS3895ADRYR"
"1","(50,1150)","0","pure_quanta","I26";
;
PART_NUMBER"AL003895003"
MATERIAL"EMPTY"
PART_TYPE"SMLF"
ROOM"DELAY1_BOM2"
VALUE"TPS3895ADRYR"
LOCATION"U117"
CDS_LMAN_SYM_OUTLINE"-275,150,275,-150"
NEEDS_NO_SIZE"TRUE"
CDS_LIB"pure_quanta"
$SEC"1"
CDS_SEC"1";
"VCC"
$PN"6"5;
"CT"
$PN"5"20;
"SENSE_OUT"
$PN"4"21;
"SENSE"
$PN"3"28;
"GND"
$PN"2"18;
"ENABLE"
$PN"1"27;
%"ADM1086AKSZREEL7"
"1","(75,1775)","0","pure_quanta","I27";
;
PART_NUMBER"AL001086001"
PART_TYPE"SMLF"
VALUE"ADM1086AKSZ-REEL7"
MATERIAL"IC"
ROOM"DELAY1_BOM1"
$LOCATION"U94"
NEEDS_NO_SIZE"TRUE"
CDS_LMAN_SYM_OUTLINE"-200,150,150,-100"
CDS_LIB"pure_quanta"
CDS_LOCATION"U94"
$SEC"1"
CDS_SEC"1";
"GND"
$PN"2"18;
"CEXT"
$PN"5"20;
"ENOUT"
$PN"4"21;
"ENIN"
$PN"1"27;
"VIN"
$PN"3"28;
"VCC"
$PN"6"5;
%"UNIVERSAL_POWER"
"1","(-1850,2400)","0","logical_power","I28";
;
HDL_POWER"P3V3_AUX"
CDS_LIB"logical_power";
"A"4;
%"UNIVERSAL_POWER"
"1","(-475,2450)","0","logical_power","I29";
;
HDL_POWER"P3V3_AUX"
CDS_LIB"logical_power";
"A"5;
%"Q_RES"
"2","(-2175,-2550)","0","pure_quanta","I3";
;
PART_NUMBER"CS41002FB09"
MATERIAL"CHIP"
WATTAGE"1/16W"
VALUE"100K"
TOLERANCE"1%"
PACK_TYPE"0402LF"
$LOCATION"R1692"
CDS_LIB"pure_quanta"
CDS_LOCATION"R1692"
$SEC"1"
CDS_SEC"1";
"A"
$PN"1"30;
"B"
$PN"2"8;
%"UNIVERSAL_GND"
"1","(675,-2825)","0","logical_power","I30";
;
CDS_LIB"logical_power"
HDL_POWER"GND";
"A"15;
%"Q_RES"
"2","(675,-2600)","0","pure_quanta","I31";
;
PART_NUMBER"CS41002FB09"
MATERIAL"EMPTY"
PACK_TYPE"0402LF"
VALUE"100K"
TOLERANCE"1%"
WATTAGE"1/16W"
$LOCATION"R4808"
CDS_LIB"pure_quanta"
CDS_LOCATION"R4808"
$SEC"1"
CDS_SEC"1";
"A"
$PN"1"24;
"B"
$PN"2"15;
%"Q_RES"
"1","(400,-2300)","0","pure_quanta","I32";
;
PART_NUMBER"CS03322FB03"
VALUE"33.2"
WATTAGE"1/16W"
MATERIAL"CHIP"
TOLERANCE"1%"
PACK_TYPE"0402LF"
$LOCATION"R1693"
CDS_LIB"pure_quanta"
CDS_LOCATION"R1693"
$SEC"1"
CDS_SEC"1";
"B"
$PN"2"24;
"A"
$PN"1"31;
%"Q_RES"
"2","(975,-1975)","2","pure_quanta","I33";
;
PART_NUMBER"CS31002FB08"
PACK_TYPE"0402LF"
MATERIAL"CHIP"
WATTAGE"1/16W"
TOLERANCE"1%"
VALUE"10K"
$LOCATION"R1694"
CDS_LIB"pure_quanta"
CDS_LOCATION"R1694"
$SEC"1"
CDS_SEC"1";
"A"
$PN"1"6;
"B"
$PN"2"24;
%"UNIVERSAL_GND"
"1","(1325,-2825)","0","logical_power","I34";
;
CDS_LIB"logical_power"
HDL_POWER"GND";
"A"16;
%"Q_CAP"
"1","(1325,-2525)","2","pure_quanta","I35";
;
PART_NUMBER"CH5104KEB02"
PACK_TYPE"C0402"
VALUE"1UF"
VOLTAGE"25V"
MATERIAL"X6S"
TOLERANCE"10%"
$LOCATION"C1319"
CDS_LIB"pure_quanta"
CDS_LOCATION"C1319"
$SEC"1"
CDS_SEC"1";
"B"
$PN"2"16;
"A"
$PN"1"24;
%"Q_RES"
"2","(1600,-2525)","0","pure_quanta","I36";
;
PART_NUMBER"CS00002JB13"
VALUE"0"
MATERIAL"EMPTY"
WATTAGE"1/16W"
TOLERANCE"5%"
PACK_TYPE"0402LF"
$LOCATION"R1695"
CDS_LIB"pure_quanta"
CDS_LOCATION"R1695"
$SEC"1"
CDS_SEC"1";
"A"
$PN"1"24;
"B"
$PN"2"25;
%"UNIVERSAL_POWER"
"1","(975,-1725)","0","logical_power","I37";
;
HDL_POWER"P3V3_AUX"
CDS_LIB"logical_power";
"A"6;
%"UNIVERSAL_GND"
"1","(875,-1050)","0","logical_power","I38";
;
CDS_LIB"logical_power"
HDL_POWER"GND";
"A"17;
%"MOSFET_NCH_GDS_ESD_PROTECTED"
"1","(900,-650)","2","pure_quanta","I39";
;
PART_NUMBER"BAM70020002"
MATERIAL"IC"
VALUE"2N7002K"
PART_TYPE"SMLF"
LOCATION"Q53"
CDS_LMAN_SYM_OUTLINE"-125,150,125,-150"
CDS_LIB"pure_quanta"
NEEDS_NO_SIZE"TRUE"
$SEC"1"
CDS_SEC"1";
"S"
$PN"S"17;
"G"
$PN"G"22;
"D"
$PN"D"23;
%"Q_RES"
"2","(-2175,-2075)","0","pure_quanta","I4";
;
PART_NUMBER"CS31002FB08"
VALUE"10K"
TOLERANCE"1%"
WATTAGE"1/16W"
MATERIAL"EMPTY"
PACK_TYPE"0402LF"
$LOCATION"R1691"
CDS_LIB"pure_quanta"
CDS_LOCATION"R1691"
$SEC"1"
CDS_SEC"1";
"A"
$PN"1"1;
"B"
$PN"2"30;
%"Q_RES"
"2","(875,-150)","0","pure_quanta","I40";
;
PART_NUMBER"CS31002FB08"
PACK_TYPE"0402LF"
WATTAGE"1/16W"
MATERIAL"CHIP"
VALUE"10K"
TOLERANCE"1%"
$LOCATION"R2486"
CDS_LIB"pure_quanta"
CDS_LOCATION"R2486"
$SEC"1"
CDS_SEC"1";
"A"
$PN"1"7;
"B"
$PN"2"23;
%"UNIVERSAL_POWER"
"1","(875,100)","0","logical_power","I41";
;
HDL_POWER"P3V3_AUX"
CDS_LIB"logical_power";
"A"7;
%"UNIVERSAL_GND"
"1","(550,875)","0","logical_power","I45";
;
HDL_POWER"GND"
CDS_LIB"logical_power";
"A"18;
%"UNIVERSAL_GND"
"1","(1425,675)","0","logical_power","I46";
;
CDS_LIB"logical_power"
HDL_POWER"GND";
"A"19;
%"Q_CAP"
"1","(1425,900)","0","pure_quanta","I47";
;
PART_NUMBER"CH3474K1B04"
MATERIAL"X7R"
TOLERANCE"10%"
VOLTAGE"25V"
VALUE"0.047UF"
PACK_TYPE"C0402"
$LOCATION"C1316"
CDS_LIB"pure_quanta"
CDS_LOCATION"C1316"
$SEC"1"
CDS_SEC"1";
"B"
$PN"2"19;
"A"
$PN"1"20;
%"UNIVERSAL_POWER"
"1","(-2175,-1825)","0","logical_power","I5";
;
HDL_POWER"P3V3_AUX"
CDS_LIB"logical_power";
"A"1;
%"UNIVERSAL_GND"
"1","(-1375,-2725)","0","logical_power","I6";
;
HDL_POWER"GND"
CDS_LIB"logical_power";
"A"9;
%"Q_CAP"
"1","(-1375,-2475)","2","pure_quanta","I7";
;
PART_NUMBER"CH5104KEB02"
VALUE"1UF"
PACK_TYPE"C0402"
TOLERANCE"10%"
MATERIAL"EMPTY"
VOLTAGE"25V"
$LOCATION"C1318"
CDS_LIB"pure_quanta"
CDS_LOCATION"C1318"
$SEC"1"
CDS_SEC"1";
"B"
$PN"2"9;
"A"
$PN"1"30;
%"UNIVERSAL_GND"
"1","(-1375,-2225)","0","logical_power","I8";
;
HDL_POWER"GND"
CDS_LIB"logical_power";
"A"10;
%"Q_CAP"
"1","(-1375,-2000)","2","pure_quanta","I9";
;
PART_NUMBER"CH4104K1B00"
PACK_TYPE"0402"
VALUE"0.1UF"
VOLTAGE"25V"
MATERIAL"X7R"
TOLERANCE"10%"
$LOCATION"C1317"
CDS_LIB"pure_quanta"
CDS_LOCATION"C1317"
$SEC"1"
CDS_SEC"1";
"B"
$PN"2"10;
"A"
$PN"1"2;
END.
